# T6G (Grand Teton) — schematic netlist excerpt (pin names and nets, part order shuffled) for the footprints in the layout excerpt that follows; sources: Cadence DE-HDL packaged netlist, KiCad conversion of 04192023_DAF0TMB3IC0_F0TG_MB_C_brd_V02_OCP.brd

R3233  Q_RES  0 5% CHIP  pkg 0402LF  page 132 : A = RST_HP_OCP_SFF_R_N ; B = RST_SMB_OCP_SFF_N
R3581  Q_RES  0 5% CHIP  pkg 0402LF  page 250 : A = SMB_INA230_3V3AUX_SDA_R ; B = SMB_INA230_3V3AUX_SDA

(kicad_pcb
	(version 20260206)
	(generator "pcbnew")
	(generator_version "10.0")
	(general
		(thickness 1.6)
		(legacy_teardrops no)
	)
	(paper "A4")
	(title_block
		(title "04192023_DAF0TMB3IC0_F0TG_MB_C_brd_V02_OCP.brd")
		(comment 1 "Grand Teton / footprints 1946-1947 of 8354")
	)
	(layers
		(0 "F.Cu" signal "TOP")
		(4 "In1.Cu" signal "GND")
		(6 "In2.Cu" signal "IN1")
		(8 "In3.Cu" signal "GND1")
		(10 "In4.Cu" signal "IN2")
		(12 "In5.Cu" signal "GND2")
		(14 "In6.Cu" signal "IN3")
		(16 "In7.Cu" signal "GND3")
		(18 "In8.Cu" signal "VCC")
		(20 "In9.Cu" signal "VCC1")
		(22 "In10.Cu" signal "GND4")
		(24 "In11.Cu" signal "IN4")
		(26 "In12.Cu" signal "GND5")
		(28 "In13.Cu" signal "IN5")
		(30 "In14.Cu" signal "GND6")
		(32 "In15.Cu" signal "IN6")
		(34 "In16.Cu" signal "GND7")
		(2 "B.Cu" signal "BOTTOM")
		(9 "F.Adhes" user "F.Adhesive")
		(11 "B.Adhes" user "B.Adhesive")
		(13 "F.Paste" user "Package Geometry/Pastemask Top")
		(15 "B.Paste" user "Package Geometry/Pastemask Bottom")
		(5 "F.SilkS" user "Ref Des/Silkscreen Top")
		(7 "B.SilkS" user "Ref Des/Silkscreen Bottom")
		(1 "F.Mask" user "Board Geometry/Soldermask Top")
		(3 "B.Mask" user "Board Geometry/Soldermask Bottom")
		(17 "Dwgs.User" user "User.Drawings")
		(19 "Cmts.User" user "User.Comments")
		(21 "Eco1.User" user "User.Eco1")
		(23 "Eco2.User" user "User.Eco2")
		(25 "Edge.Cuts" user "Board Geometry/Outline")
		(27 "Margin" user)
		(31 "F.CrtYd" user "Package Geometry/Place Bound Top")
		(29 "B.CrtYd" user "Package Geometry/Place Bound Bottom")
		(35 "F.Fab" user "Ref Des/Assembly Top")
		(33 "B.Fab" user "Ref Des/Assembly Bottom")
	)
	(footprint ""
		(layer "F.Cu")
		(at 463.735928 -94.317566)
		(property "Reference" "R3233"
			(at 0 0 0)
			(layer "F.SilkS")
			(hide yes)
			(effects
				(font
					(size 1.27 1.27)
				)
			)
		)
		(property "Value" ""
			(at 0 0 0)
			(layer "F.Fab")
			(effects
				(font
					(size 1.27 1.27)
				)
			)
		)
		(duplicate_pad_numbers_are_jumpers no)
		(fp_line
			(start -0.7874 -0.4064)
			(end 0.7874 -0.4064)
			(stroke
				(width 0.1524)
				(type default)
			)
			(layer "F.SilkS")
		)
		(fp_line
			(start -0.7874 0.4064)
			(end -0.7874 -0.4064)
			(stroke
				(width 0.1524)
				(type default)
			)
			(layer "F.SilkS")
		)
		(fp_line
			(start 0.7874 -0.4064)
			(end 0.7874 0.4064)
			(stroke
				(width 0.1524)
				(type default)
			)
			(layer "F.SilkS")
		)
		(fp_line
			(start 0.7874 0.4064)
			(end -0.7874 0.4064)
			(stroke
				(width 0.1524)
				(type default)
			)
			(layer "F.SilkS")
		)
		(fp_line
			(start -0.67945 -0.305054)
			(end -0.12065 -0.305054)
			(stroke
				(width 0.1)
				(type default)
			)
			(layer "F.Fab")
		)
		(fp_line
			(start -0.67945 0.3048)
			(end -0.67945 -0.305054)
			(stroke
				(width 0.1)
				(type default)
			)
			(layer "F.Fab")
		)
		(fp_line
			(start -0.12065 -0.305054)
			(end -0.12065 -0.2794)
			(stroke
				(width 0.1)
				(type default)
			)
			(layer "F.Fab")
		)
		(fp_line
			(start -0.12065 -0.2794)
			(end 0.12065 -0.2794)
			(stroke
				(width 0.1)
				(type default)
			)
			(layer "F.Fab")
		)
		(fp_line
			(start -0.12065 0.2794)
			(end -0.12065 0.3048)
			(stroke
				(width 0.1)
				(type default)
			)
			(layer "F.Fab")
		)
		(fp_line
			(start -0.12065 0.3048)
			(end -0.67945 0.3048)
			(stroke
				(width 0.1)
				(type default)
			)
			(layer "F.Fab")
		)
		(fp_line
			(start 0.120396 0.2794)
			(end -0.12065 0.2794)
			(stroke
				(width 0.1)
				(type default)
			)
			(layer "F.Fab")
		)
		(fp_line
			(start 0.120396 0.3048)
			(end 0.120396 0.2794)
			(stroke
				(width 0.1)
				(type default)
			)
			(layer "F.Fab")
		)
		(fp_line
			(start 0.12065 -0.3048)
			(end 0.67945 -0.3048)
			(stroke
				(width 0.1)
				(type default)
			)
			(layer "F.Fab")
		)
		(fp_line
			(start 0.12065 -0.2794)
			(end 0.12065 -0.3048)
			(stroke
				(width 0.1)
				(type default)
			)
			(layer "F.Fab")
		)
		(fp_line
			(start 0.67945 -0.3048)
			(end 0.67945 0.3048)
			(stroke
				(width 0.1)
				(type default)
			)
			(layer "F.Fab")
		)
		(fp_line
			(start 0.67945 0.3048)
			(end 0.120396 0.3048)
			(stroke
				(width 0.1)
				(type default)
			)
			(layer "F.Fab")
		)
		(pad "1" smd circle
			(at -0.40005 0)
			(size 0 0)
			(layers "F.Cu" "F.Mask" "F.Paste")
			(net "RST_HP_OCP_SFF_R_N")
		)
		(pad "2" smd circle
			(at 0.40005 0)
			(size 0 0)
			(layers "F.Cu" "F.Mask" "F.Paste")
			(net "RST_SMB_OCP_SFF_N")
		)
	)
	(footprint ""
		(layer "F.Cu")
		(at 294.421052 -118.285514)
		(property "Reference" "R3581"
			(at 0 0 0)
			(layer "F.SilkS")
			(hide yes)
			(effects
				(font
					(size 1.27 1.27)
				)
			)
		)
		(property "Value" ""
			(at 0 0 0)
			(layer "F.Fab")
			(effects
				(font
					(size 1.27 1.27)
				)
			)
		)
		(duplicate_pad_numbers_are_jumpers no)
		(fp_line
			(start -0.7874 -0.4064)
			(end 0.7874 -0.4064)
			(stroke
				(width 0.1524)
				(type default)
			)
			(layer "F.SilkS")
		)
		(fp_line
			(start -0.7874 0.4064)
			(end -0.7874 -0.4064)
			(stroke
				(width 0.1524)
				(type default)
			)
			(layer "F.SilkS")
		)
		(fp_line
			(start 0.7874 -0.4064)
			(end 0.7874 0.4064)
			(stroke
				(width 0.1524)
				(type default)
			)
			(layer "F.SilkS")
		)
		(fp_line
			(start 0.7874 0.4064)
			(end -0.7874 0.4064)
			(stroke
				(width 0.1524)
				(type default)
			)
			(layer "F.SilkS")
		)
		(fp_line
			(start -0.67945 -0.305054)
			(end -0.12065 -0.305054)
			(stroke
				(width 0.1)
				(type default)
			)
			(layer "F.Fab")
		)
		(fp_line
			(start -0.67945 0.3048)
			(end -0.67945 -0.305054)
			(stroke
				(width 0.1)
				(type default)
			)
			(layer "F.Fab")
		)
		(fp_line
			(start -0.12065 -0.305054)
			(end -0.12065 -0.2794)
			(stroke
				(width 0.1)
				(type default)
			)
			(layer "F.Fab")
		)
		(fp_line
			(start -0.12065 -0.2794)
			(end 0.12065 -0.2794)
			(stroke
				(width 0.1)
				(type default)
			)
			(layer "F.Fab")
		)
		(fp_line
			(start -0.12065 0.2794)
			(end -0.12065 0.3048)
			(stroke
				(width 0.1)
				(type default)
			)
			(layer "F.Fab")
		)
		(fp_line
			(start -0.12065 0.3048)
			(end -0.67945 0.3048)
			(stroke
				(width 0.1)
				(type default)
			)
			(layer "F.Fab")
		)
		(fp_line
			(start 0.120396 0.2794)
			(end -0.12065 0.2794)
			(stroke
				(width 0.1)
				(type default)
			)
			(layer "F.Fab")
		)
		(fp_line
			(start 0.120396 0.3048)
			(end 0.120396 0.2794)
			(stroke
				(width 0.1)
				(type default)
			)
			(layer "F.Fab")
		)
		(fp_line
			(start 0.12065 -0.3048)
			(end 0.67945 -0.3048)
			(stroke
				(width 0.1)
				(type default)
			)
			(layer "F.Fab")
		)
		(fp_line
			(start 0.12065 -0.2794)
			(end 0.12065 -0.3048)
			(stroke
				(width 0.1)
				(type default)
			)
			(layer "F.Fab")
		)
		(fp_line
			(start 0.67945 -0.3048)
			(end 0.67945 0.3048)
			(stroke
				(width 0.1)
				(type default)
			)
			(layer "F.Fab")
		)
		(fp_line
			(start 0.67945 0.3048)
			(end 0.120396 0.3048)
			(stroke
				(width 0.1)
				(type default)
			)
			(layer "F.Fab")
		)
		(pad "1" smd circle
			(at -0.40005 0)
			(size 0 0)
			(layers "F.Cu" "F.Mask" "F.Paste")
			(net "SMB_INA230_3V3AUX_SDA_R")
		)
		(pad "2" smd circle
			(at 0.40005 0)
			(size 0 0)
			(layers "F.Cu" "F.Mask" "F.Paste")
			(net "SMB_INA230_3V3AUX_SDA")
		)
	)
)
